# SCM (Grand Teton) — schematic netlist excerpt (pin names and nets, part order shuffled) for the footprints in the layout excerpt that follows; sources: Cadence DE-HDL packaged netlist, KiCad conversion of 12092022_DA0F0TMDCD0_F0T_Management_Board_D_brd_V3_OCP.brd

OSC1  OSC4_7X25000018  25MHZ MISC  pkg X_7X  page 15
  OE  = PU_25M_BMC_CLK_EN
  GND  = GND
  \out\  = BMC_CLK_25M_R
  VDD  = P3V3_RGM

R376  Q_RES  4.7K 1% CHIP  pkg 0402LF  page 28 : A = P5V_AUX ; B = USB_OC0_EN

(kicad_pcb
	(version 20260206)
	(generator "pcbnew")
	(generator_version "10.0")
	(general
		(thickness 1.6)
		(legacy_teardrops no)
	)
	(paper "A4")
	(title_block
		(title "12092022_DA0F0TMDCD0_F0T_Management_Board_D_brd_V3_OCP.brd")
		(comment 1 "Grand Teton / footprints 289-290 of 1440")
	)
	(layers
		(0 "F.Cu" signal "TOP")
		(4 "In1.Cu" signal "GND")
		(6 "In2.Cu" signal "IN1")
		(8 "In3.Cu" signal "GND1")
		(10 "In4.Cu" signal "IN2")
		(12 "In5.Cu" signal "VCC")
		(14 "In6.Cu" signal "VCC1")
		(16 "In7.Cu" signal "IN3")
		(18 "In8.Cu" signal "GND2")
		(20 "In9.Cu" signal "IN4")
		(22 "In10.Cu" signal "GND3")
		(2 "B.Cu" signal "BOTTOM")
		(9 "F.Adhes" user "F.Adhesive")
		(11 "B.Adhes" user "B.Adhesive")
		(13 "F.Paste" user "Package Geometry/Pastemask Top")
		(15 "B.Paste" user "Package Geometry/Pastemask Bottom")
		(5 "F.SilkS" user "Ref Des/Silkscreen Top")
		(7 "B.SilkS" user "Ref Des/Silkscreen Bottom")
		(1 "F.Mask" user "Board Geometry/Soldermask Top")
		(3 "B.Mask" user "Board Geometry/Soldermask Bottom")
		(17 "Dwgs.User" user "User.Drawings")
		(19 "Cmts.User" user "User.Comments")
		(21 "Eco1.User" user "User.Eco1")
		(23 "Eco2.User" user "User.Eco2")
		(25 "Edge.Cuts" user "Board Geometry/Outline")
		(27 "Margin" user)
		(31 "F.CrtYd" user "Package Geometry/Place Bound Top")
		(29 "B.CrtYd" user "Package Geometry/Place Bound Bottom")
		(35 "F.Fab" user "Ref Des/Assembly Top")
		(33 "B.Fab" user "Ref Des/Assembly Bottom")
	)
	(footprint ""
		(layer "F.Cu")
		(at 57.073292 -28.062936 90)
		(property "Reference" "OSC1"
			(at -2.448306 1.397508 0)
			(unlocked yes)
			(layer "F.SilkS")
			(effects
				(font
					(size 0.7874 0.5842)
					(thickness 0.1524)
				)
				(justify left)
			)
		)
		(property "Value" ""
			(at 0 0 90)
			(layer "F.Fab")
			(effects
				(font
					(size 1.27 1.27)
				)
			)
		)
		(duplicate_pad_numbers_are_jumpers no)
		(fp_line
			(start 1.397 -1.761236)
			(end -1.397 -1.761236)
			(stroke
				(width 0.1524)
				(type default)
			)
			(layer "F.SilkS")
		)
		(fp_line
			(start -1.397 -1.761236)
			(end -1.397 1.761236)
			(stroke
				(width 0.1524)
				(type default)
			)
			(layer "F.SilkS")
		)
		(fp_line
			(start 1.397 1.761236)
			(end 1.397 -1.761236)
			(stroke
				(width 0.1524)
				(type default)
			)
			(layer "F.SilkS")
		)
		(fp_line
			(start -1.397 1.761236)
			(end 1.397 1.761236)
			(stroke
				(width 0.1524)
				(type default)
			)
			(layer "F.SilkS")
		)
		(fp_poly
			(pts
				(xy -1.69037 -0.799338) (xy -2.70637 -1.307592) (xy -2.706624 -0.291592)
			)
			(stroke
				(width 0)
				(type default)
			)
			(fill yes)
			(layer "F.SilkS")
		)
		(fp_line
			(start 1.299972 -1.649984)
			(end 1.299972 1.649984)
			(stroke
				(width 0.1)
				(type default)
			)
			(layer "F.Fab")
		)
		(fp_line
			(start -1.299972 -1.649984)
			(end 1.299972 -1.649984)
			(stroke
				(width 0.1)
				(type default)
			)
			(layer "F.Fab")
		)
		(fp_line
			(start 1.299972 1.649984)
			(end -1.299972 1.649984)
			(stroke
				(width 0.1)
				(type default)
			)
			(layer "F.Fab")
		)
		(fp_line
			(start -1.299972 1.649984)
			(end -1.299972 -1.649984)
			(stroke
				(width 0.1)
				(type default)
			)
			(layer "F.Fab")
		)
		(fp_poly
			(pts
				(xy -1.694688 -1.050036) (xy -2.710688 -1.558036) (xy -2.710688 -0.542036)
			)
			(stroke
				(width 0)
				(type default)
			)
			(fill yes)
			(layer "F.Fab")
		)
		(pad "1" smd rect
			(at -0.824992 -1.050036 90)
			(size 0.8636 1.1684)
			(layers "F.Cu" "F.Mask" "F.Paste")
			(net "PU_25M_BMC_CLK_EN")
		)
		(pad "2" smd rect
			(at -0.824992 1.050036 90)
			(size 0.8636 1.1684)
			(layers "F.Cu" "F.Mask" "F.Paste")
			(net "GND")
		)
		(pad "3" smd rect
			(at 0.824992 1.050036 90)
			(size 0.8636 1.1684)
			(layers "F.Cu" "F.Mask" "F.Paste")
			(net "BMC_CLK_25M_R")
		)
		(pad "4" smd rect
			(at 0.824992 -1.050036 90)
			(size 0.8636 1.1684)
			(layers "F.Cu" "F.Mask" "F.Paste")
			(net "P3V3_RGM")
		)
	)
	(footprint ""
		(layer "F.Cu")
		(at 54.84368 -25.911556 180)
		(property "Reference" "R376"
			(at 0 0 180)
			(layer "F.SilkS")
			(hide yes)
			(effects
				(font
					(size 1.27 1.27)
				)
			)
		)
		(property "Value" ""
			(at 0 0 180)
			(layer "F.Fab")
			(effects
				(font
					(size 1.27 1.27)
				)
			)
		)
		(duplicate_pad_numbers_are_jumpers no)
		(fp_line
			(start 0.7874 0.4064)
			(end -0.7874 0.4064)
			(stroke
				(width 0.1524)
				(type default)
			)
			(layer "F.SilkS")
		)
		(fp_line
			(start 0.7874 -0.4064)
			(end 0.7874 0.4064)
			(stroke
				(width 0.1524)
				(type default)
			)
			(layer "F.SilkS")
		)
		(fp_line
			(start -0.7874 0.4064)
			(end -0.7874 -0.4064)
			(stroke
				(width 0.1524)
				(type default)
			)
			(layer "F.SilkS")
		)
		(fp_line
			(start -0.7874 -0.4064)
			(end 0.7874 -0.4064)
			(stroke
				(width 0.1524)
				(type default)
			)
			(layer "F.SilkS")
		)
		(fp_line
			(start 0.67945 0.3048)
			(end 0.120396 0.3048)
			(stroke
				(width 0.1)
				(type default)
			)
			(layer "F.Fab")
		)
		(fp_line
			(start 0.67945 -0.3048)
			(end 0.67945 0.3048)
			(stroke
				(width 0.1)
				(type default)
			)
			(layer "F.Fab")
		)
		(fp_line
			(start 0.12065 -0.2794)
			(end 0.12065 -0.3048)
			(stroke
				(width 0.1)
				(type default)
			)
			(layer "F.Fab")
		)
		(fp_line
			(start 0.12065 -0.3048)
			(end 0.67945 -0.3048)
			(stroke
				(width 0.1)
				(type default)
			)
			(layer "F.Fab")
		)
		(fp_line
			(start 0.120396 0.3048)
			(end 0.120396 0.2794)
			(stroke
				(width 0.1)
				(type default)
			)
			(layer "F.Fab")
		)
		(fp_line
			(start 0.120396 0.2794)
			(end -0.12065 0.2794)
			(stroke
				(width 0.1)
				(type default)
			)
			(layer "F.Fab")
		)
		(fp_line
			(start -0.12065 0.3048)
			(end -0.67945 0.3048)
			(stroke
				(width 0.1)
				(type default)
			)
			(layer "F.Fab")
		)
		(fp_line
			(start -0.12065 0.2794)
			(end -0.12065 0.3048)
			(stroke
				(width 0.1)
				(type default)
			)
			(layer "F.Fab")
		)
		(fp_line
			(start -0.12065 -0.2794)
			(end 0.12065 -0.2794)
			(stroke
				(width 0.1)
				(type default)
			)
			(layer "F.Fab")
		)
		(fp_line
			(start -0.12065 -0.305054)
			(end -0.12065 -0.2794)
			(stroke
				(width 0.1)
				(type default)
			)
			(layer "F.Fab")
		)
		(fp_line
			(start -0.67945 0.3048)
			(end -0.67945 -0.305054)
			(stroke
				(width 0.1)
				(type default)
			)
			(layer "F.Fab")
		)
		(fp_line
			(start -0.67945 -0.305054)
			(end -0.12065 -0.305054)
			(stroke
				(width 0.1)
				(type default)
			)
			(layer "F.Fab")
		)
		(pad "1" smd circle
			(at -0.40005 0 180)
			(size 0 0)
			(layers "F.Cu" "F.Mask" "F.Paste")
			(net "P5V_AUX")
		)
		(pad "2" smd circle
			(at 0.40005 0 180)
			(size 0 0)
			(layers "F.Cu" "F.Mask" "F.Paste")
			(net "USB_OC0_EN")
		)
	)
)
